FILE_TYPE = CONNECTIVITY;
{Allegro Design Entry HDL 17.4-2019 S026 (4007227) 1/17/2022}
"PAGE_NUMBER" = 351;
0"NC";
1"P5E_CPU0_P1_TX_C_DP<7:0>";
2"P5E_CPU0_P1_TX_C_DN<15:8>";
3"P5E_CPU0_P1_TX_DP<7:0>";
4"P5E_CPU0_P1_TX_DN<7:0>";
5"P5E_CPU0_P1_TX_DN<15:8>";
6"P5E_CPU0_P0_TX_C_DN<15:8>";
7"P5E_CPU0_P0_TX_C_DP<7:0>";
8"P5E_CPU0_P0_TX_C_DN<7:0>";
9"P5E_CPU0_P0_TX_C_DP<15:8>";
10"P5E_CPU0_P0_TX_DP<7:0>";
11"P5E_CPU0_P0_TX_DP<15:8>";
12"P5E_CPU0_P0_TX_DN<15:8>";
13"P5E_CPU0_P0_TX_DN<7:0>";
14"P5E_CPU0_P1_TX_DP<15:8>";
15"P5E_CPU0_P1_TX_C_DP<15:8>";
16"P5E_CPU0_P1_TX_C_DN<7:0>";
17"P5E_CPU0_P0_TX_C_DN<15>";
18"P5E_CPU0_P0_TX_DP<15>";
19"P5E_CPU0_P1_TX_C_DN<0>";
20"P5E_CPU0_P1_TX_C_DN<3>";
21"P5E_CPU0_P1_TX_C_DN<6>";
22"P5E_CPU0_P1_TX_C_DN<5>";
23"P5E_CPU0_P1_TX_C_DN<4>";
24"P5E_CPU0_P1_TX_C_DN<7>";
25"P5E_CPU0_P1_TX_C_DN<1>";
26"P5E_CPU0_P1_TX_C_DN<2>";
27"P5E_CPU0_P1_TX_C_DP<14>";
28"P5E_CPU0_P1_TX_C_DP<15>";
29"P5E_CPU0_P1_TX_C_DP<13>";
30"P5E_CPU0_P1_TX_C_DP<12>";
31"P5E_CPU0_P1_TX_C_DP<9>";
32"P5E_CPU0_P1_TX_C_DP<8>";
33"P5E_CPU0_P1_TX_C_DP<11>";
34"P5E_CPU0_P1_TX_C_DP<10>";
35"P5E_CPU0_P1_TX_DN<15>";
36"P5E_CPU0_P1_TX_DN<14>";
37"P5E_CPU0_P1_TX_DP<14>";
38"P5E_CPU0_P1_TX_DN<8>";
39"P5E_CPU0_P1_TX_DP<9>";
40"P5E_CPU0_P1_TX_DP<10>";
41"P5E_CPU0_P1_TX_DP<11>";
42"P5E_CPU0_P1_TX_DP<12>";
43"P5E_CPU0_P1_TX_DP<13>";
44"P5E_CPU0_P1_TX_DP<15>";
45"P5E_CPU0_P1_TX_DP<8>";
46"P5E_CPU0_P1_TX_DN<5>";
47"P5E_CPU0_P1_TX_DN<4>";
48"P5E_CPU0_P1_TX_DN<11>";
49"P5E_CPU0_P1_TX_DN<9>";
50"P5E_CPU0_P1_TX_DP<7>";
51"P5E_CPU0_P0_TX_C_DP<8>";
52"P5E_CPU0_P0_TX_DN<8>";
53"P5E_CPU0_P0_TX_DP<11>";
54"P5E_CPU0_P0_TX_C_DP<11>";
55"P5E_CPU0_P0_TX_C_DP<10>";
56"P5E_CPU0_P0_TX_DP<10>";
57"P5E_CPU0_P0_TX_DP<8>";
58"P5E_CPU0_P0_TX_DN<10>";
59"P5E_CPU0_P0_TX_DN<14>";
60"P5E_CPU0_P0_TX_DN<15>";
61"P5E_CPU0_P0_TX_DN<7>";
62"P5E_CPU0_P0_TX_DN<1>";
63"P5E_CPU0_P0_TX_DN<5>";
64"P5E_CPU0_P0_TX_DN<3>";
65"P5E_CPU0_P0_TX_DN<2>";
66"P5E_CPU0_P0_TX_DN<0>";
67"P5E_CPU0_P0_TX_DN<4>";
68"P5E_CPU0_P0_TX_DN<6>";
69"P5E_CPU0_P0_TX_DN<13>";
70"P5E_CPU0_P0_TX_DN<12>";
71"P5E_CPU0_P0_TX_DN<11>";
72"P5E_CPU0_P0_TX_DN<9>";
73"P5E_CPU0_P0_TX_DP<12>";
74"P5E_CPU0_P0_TX_DP<13>";
75"P5E_CPU0_P0_TX_DP<14>";
76"P5E_CPU0_P0_TX_DP<9>";
77"P5E_CPU0_P0_TX_C_DP<6>";
78"P5E_CPU0_P0_TX_C_DN<6>";
79"P5E_CPU0_P0_TX_C_DP<7>";
80"P5E_CPU0_P0_TX_C_DN<7>";
81"P5E_CPU0_P0_TX_C_DN<8>";
82"P5E_CPU0_P0_TX_C_DP<9>";
83"P5E_CPU0_P0_TX_DP<7>";
84"P5E_CPU0_P0_TX_C_DP<0>";
85"P5E_CPU0_P0_TX_C_DP<2>";
86"P5E_CPU0_P0_TX_C_DN<2>";
87"P5E_CPU0_P0_TX_DP<4>";
88"P5E_CPU0_P0_TX_DP<5>";
89"P5E_CPU0_P0_TX_DP<3>";
90"P5E_CPU0_P0_TX_C_DN<9>";
91"P5E_CPU0_P0_TX_DP<0>";
92"P5E_CPU0_P0_TX_DP<1>";
93"P5E_CPU0_P0_TX_DP<6>";
94"P5E_CPU0_P0_TX_DP<2>";
95"P5E_CPU0_P0_TX_C_DN<13>";
96"P5E_CPU0_P0_TX_C_DP<14>";
97"P5E_CPU0_P0_TX_C_DP<15>";
98"P5E_CPU0_P0_TX_C_DN<11>";
99"P5E_CPU0_P0_TX_C_DP<13>";
100"P5E_CPU0_P0_TX_C_DN<12>";
101"P5E_CPU0_P0_TX_C_DP<12>";
102"P5E_CPU0_P0_TX_C_DN<14>";
103"P5E_CPU0_P0_TX_C_DN<5>";
104"P5E_CPU0_P0_TX_C_DP<5>";
105"P5E_CPU0_P0_TX_C_DP<1>";
106"P5E_CPU0_P0_TX_C_DN<1>";
107"P5E_CPU0_P0_TX_C_DN<4>";
108"P5E_CPU0_P0_TX_C_DN<0>";
109"P5E_CPU0_P0_TX_C_DN<3>";
110"P5E_CPU0_P0_TX_C_DP<4>";
111"P5E_CPU0_P0_TX_C_DP<3>";
112"P5E_CPU0_P0_TX_C_DN<10>";
113"P5E_CPU0_P1_TX_DN<0>";
114"P5E_CPU0_P1_TX_DP<2>";
115"P5E_CPU0_P1_TX_DP<1>";
116"P5E_CPU0_P1_TX_DP<4>";
117"P5E_CPU0_P1_TX_DN<3>";
118"P5E_CPU0_P1_TX_DP<3>";
119"P5E_CPU0_P1_TX_DN<1>";
120"P5E_CPU0_P1_TX_DN<2>";
121"P5E_CPU0_P1_TX_DN<12>";
122"P5E_CPU0_P1_TX_DN<10>";
123"P5E_CPU0_P1_TX_DN<13>";
124"P5E_CPU0_P1_TX_DN<7>";
125"P5E_CPU0_P1_TX_DN<6>";
126"P5E_CPU0_P1_TX_DP<6>";
127"P5E_CPU0_P1_TX_DP<5>";
128"P5E_CPU0_P1_TX_DP<0>";
129"P5E_CPU0_P1_TX_C_DN<11>";
130"P5E_CPU0_P1_TX_C_DN<12>";
131"P5E_CPU0_P1_TX_C_DN<8>";
132"P5E_CPU0_P1_TX_C_DN<14>";
133"P5E_CPU0_P1_TX_C_DN<9>";
134"P5E_CPU0_P1_TX_C_DN<10>";
135"P5E_CPU0_P1_TX_C_DN<13>";
136"P5E_CPU0_P1_TX_C_DN<15>";
137"P5E_CPU0_P1_TX_C_DP<1>";
138"P5E_CPU0_P1_TX_C_DP<2>";
139"P5E_CPU0_P1_TX_C_DP<3>";
140"P5E_CPU0_P1_TX_C_DP<0>";
141"P5E_CPU0_P1_TX_C_DP<5>";
142"P5E_CPU0_P1_TX_C_DP<7>";
143"P5E_CPU0_P1_TX_C_DP<6>";
144"P5E_CPU0_P1_TX_C_DP<4>";
%"TAP"
"1","(-1550,925)","2","standard","I10";
;
CDS_LIB"standard"
BODY_TYPE"PLUMBING"
HDL_TAP"TRUE";
"B \NAC \NWC"10;
"S \NAC"
BN"3"89;
%"TAP"
"1","(175,2700)","0","standard","I100";
;
CDS_LIB"standard"
BODY_TYPE"PLUMBING"
HDL_TAP"TRUE";
"B \NAC \NWC"9;
"S \NAC"
BN"10"55;
%"TAP"
"1","(175,3100)","0","standard","I101";
;
CDS_LIB"standard"
BODY_TYPE"PLUMBING"
HDL_TAP"TRUE";
"B \NAC \NWC"9;
"S \NAC"
BN"12"101;
%"TAP"
"1","(175,3300)","0","standard","I102";
;
CDS_LIB"standard"
BODY_TYPE"PLUMBING"
HDL_TAP"TRUE";
"B \NAC \NWC"9;
"S \NAC"
BN"13"99;
%"TAP"
"1","(175,3500)","0","standard","I103";
;
CDS_LIB"standard"
BODY_TYPE"PLUMBING"
HDL_TAP"TRUE";
"B \NAC \NWC"9;
"S \NAC"
BN"14"96;
%"TAP"
"1","(175,3700)","0","standard","I104";
;
CDS_LIB"standard"
BODY_TYPE"PLUMBING"
HDL_TAP"TRUE";
"B \NAC \NWC"9;
"S \NAC"
BN"15"97;
%"TAP"
"1","(3000,525)","2","standard","I109";
;
CDS_LIB"standard"
BODY_TYPE"PLUMBING"
HDL_TAP"TRUE";
"B \NAC \NWC"3;
"S \NAC"
BN"1"115;
%"TAP"
"1","(-1550,1125)","2","standard","I11";
;
CDS_LIB"standard"
BODY_TYPE"PLUMBING"
HDL_TAP"TRUE";
"B \NAC \NWC"10;
"S \NAC"
BN"4"87;
%"TAP"
"1","(3000,325)","2","standard","I110";
;
CDS_LIB"standard"
BODY_TYPE"PLUMBING"
HDL_TAP"TRUE";
"B \NAC \NWC"3;
"S \NAC"
BN"0"128;
%"TAP"
"1","(3000,925)","2","standard","I111";
;
CDS_LIB"standard"
BODY_TYPE"PLUMBING"
HDL_TAP"TRUE";
"B \NAC \NWC"3;
"S \NAC"
BN"3"118;
%"TAP"
"1","(3000,725)","2","standard","I112";
;
CDS_LIB"standard"
BODY_TYPE"PLUMBING"
HDL_TAP"TRUE";
"B \NAC \NWC"3;
"S \NAC"
BN"2"114;
%"TAP"
"1","(3000,1525)","2","standard","I113";
;
CDS_LIB"standard"
BODY_TYPE"PLUMBING"
HDL_TAP"TRUE";
"B \NAC \NWC"3;
"S \NAC"
BN"6"126;
%"TAP"
"1","(3000,1325)","2","standard","I114";
;
CDS_LIB"standard"
BODY_TYPE"PLUMBING"
HDL_TAP"TRUE";
"B \NAC \NWC"3;
"S \NAC"
BN"5"127;
%"TAP"
"1","(3000,1125)","2","standard","I115";
;
CDS_LIB"standard"
BODY_TYPE"PLUMBING"
HDL_TAP"TRUE";
"B \NAC \NWC"3;
"S \NAC"
BN"4"116;
%"TAP"
"1","(3000,1725)","2","standard","I116";
;
CDS_LIB"standard"
BODY_TYPE"PLUMBING"
HDL_TAP"TRUE";
"B \NAC \NWC"3;
"S \NAC"
BN"7"50;
%"TAP"
"1","(3250,375)","2","standard","I117";
;
CDS_LIB"standard"
BODY_TYPE"PLUMBING"
HDL_TAP"TRUE";
"B \NAC \NWC"4;
"S \NAC"
BN"0"113;
%"TAP"
"1","(3250,575)","2","standard","I118";
;
CDS_LIB"standard"
BODY_TYPE"PLUMBING"
HDL_TAP"TRUE";
"B \NAC \NWC"4;
"S \NAC"
BN"1"119;
%"TAP"
"1","(3250,775)","2","standard","I119";
;
CDS_LIB"standard"
BODY_TYPE"PLUMBING"
HDL_TAP"TRUE";
"B \NAC \NWC"4;
"S \NAC"
BN"2"120;
%"TAP"
"1","(-1300,775)","2","standard","I12";
;
CDS_LIB"standard"
BODY_TYPE"PLUMBING"
HDL_TAP"TRUE";
"B \NAC \NWC"13;
"S \NAC"
BN"2"65;
%"TAP"
"1","(3250,975)","2","standard","I120";
;
CDS_LIB"standard"
BODY_TYPE"PLUMBING"
HDL_TAP"TRUE";
"B \NAC \NWC"4;
"S \NAC"
BN"3"117;
%"Q_CAP_DIFFBUS"
"2","(3975,325)","2","pure_quanta","I121";
;
LOCATION"C965"
$SEC"1"
CDS_SEC"1"
VALUE"DIFF BUS_0.22UF"
PIN_NAMES_ROTATE"TRUE"
CDS_LIB"pure_quanta"
CDS_LMAN_SYM_OUTLINE"-25,50,25,-50"
VOLTAGE"6.3V"
MATERIAL"X6S"
PACK_TYPE"C0201"
TOLERANCE"20%"
PART_NUMBER"SP_CH4221MEE01"
LOCATION"C965";
"2"
$PN"2"128;
"1"
$PN"1"140;
%"Q_CAP_DIFFBUS"
"2","(3975,375)","2","pure_quanta","I122";
;
LOCATION"C964"
$SEC"1"
CDS_SEC"1"
VALUE"DIFF BUS_0.22UF"
PIN_NAMES_ROTATE"TRUE"
CDS_LIB"pure_quanta"
CDS_LMAN_SYM_OUTLINE"-25,50,25,-50"
VOLTAGE"6.3V"
MATERIAL"X6S"
PACK_TYPE"C0201"
TOLERANCE"20%"
PART_NUMBER"SP_CH4221MEE01"
LOCATION"C964";
"2"
$PN"2"113;
"1"
$PN"1"19;
%"Q_CAP_DIFFBUS"
"2","(3975,525)","2","pure_quanta","I123";
;
LOCATION"C963"
$SEC"1"
CDS_SEC"1"
VALUE"DIFF BUS_0.22UF"
PIN_NAMES_ROTATE"TRUE"
CDS_LIB"pure_quanta"
CDS_LMAN_SYM_OUTLINE"-25,50,25,-50"
VOLTAGE"6.3V"
MATERIAL"X6S"
PACK_TYPE"C0201"
TOLERANCE"20%"
PART_NUMBER"SP_CH4221MEE01"
LOCATION"C963";
"2"
$PN"2"115;
"1"
$PN"1"137;
%"Q_CAP_DIFFBUS"
"2","(3975,575)","2","pure_quanta","I124";
;
LOCATION"C962"
$SEC"1"
CDS_SEC"1"
VALUE"DIFF BUS_0.22UF"
PIN_NAMES_ROTATE"TRUE"
CDS_LMAN_SYM_OUTLINE"-25,50,25,-50"
CDS_LIB"pure_quanta"
VOLTAGE"6.3V"
MATERIAL"X6S"
PACK_TYPE"C0201"
TOLERANCE"20%"
PART_NUMBER"SP_CH4221MEE01"
LOCATION"C962";
"2"
$PN"2"119;
"1"
$PN"1"25;
%"Q_CAP_DIFFBUS"
"2","(3975,725)","2","pure_quanta","I125";
;
LOCATION"C961"
$SEC"1"
CDS_SEC"1"
VALUE"DIFF BUS_0.22UF"
PIN_NAMES_ROTATE"TRUE"
CDS_LIB"pure_quanta"
CDS_LMAN_SYM_OUTLINE"-25,50,25,-50"
VOLTAGE"6.3V"
MATERIAL"X6S"
PACK_TYPE"C0201"
TOLERANCE"20%"
PART_NUMBER"SP_CH4221MEE01"
LOCATION"C961";
"2"
$PN"2"114;
"1"
$PN"1"138;
%"Q_CAP_DIFFBUS"
"2","(3975,775)","2","pure_quanta","I126";
;
LOCATION"C960"
$SEC"1"
CDS_SEC"1"
VALUE"DIFF BUS_0.22UF"
PIN_NAMES_ROTATE"TRUE"
CDS_LIB"pure_quanta"
CDS_LMAN_SYM_OUTLINE"-25,50,25,-50"
VOLTAGE"6.3V"
MATERIAL"X6S"
PACK_TYPE"C0201"
TOLERANCE"20%"
PART_NUMBER"SP_CH4221MEE01"
LOCATION"C960";
"2"
$PN"2"120;
"1"
$PN"1"26;
%"Q_CAP_DIFFBUS"
"2","(3975,925)","2","pure_quanta","I127";
;
LOCATION"C959"
$SEC"1"
CDS_SEC"1"
VALUE"DIFF BUS_0.22UF"
PIN_NAMES_ROTATE"TRUE"
CDS_LMAN_SYM_OUTLINE"-25,50,25,-50"
CDS_LIB"pure_quanta"
VOLTAGE"6.3V"
MATERIAL"X6S"
PACK_TYPE"C0201"
TOLERANCE"20%"
PART_NUMBER"SP_CH4221MEE01"
LOCATION"C959";
"2"
$PN"2"118;
"1"
$PN"1"139;
%"Q_CAP_DIFFBUS"
"2","(3975,975)","2","pure_quanta","I128";
;
LOCATION"C958"
$SEC"1"
CDS_SEC"1"
VALUE"DIFF BUS_0.22UF"
PIN_NAMES_ROTATE"TRUE"
CDS_LMAN_SYM_OUTLINE"-25,50,25,-50"
CDS_LIB"pure_quanta"
VOLTAGE"6.3V"
MATERIAL"X6S"
PACK_TYPE"C0201"
TOLERANCE"20%"
PART_NUMBER"SP_CH4221MEE01"
LOCATION"C958";
"2"
$PN"2"117;
"1"
$PN"1"20;
%"TAP"
"1","(3250,1375)","2","standard","I129";
;
CDS_LIB"standard"
BODY_TYPE"PLUMBING"
HDL_TAP"TRUE";
"B \NAC \NWC"4;
"S \NAC"
BN"5"46;
%"TAP"
"1","(-1300,975)","2","standard","I13";
;
CDS_LIB"standard"
BODY_TYPE"PLUMBING"
HDL_TAP"TRUE";
"B \NAC \NWC"13;
"S \NAC"
BN"3"64;
%"TAP"
"1","(3250,1175)","2","standard","I130";
;
CDS_LIB"standard"
BODY_TYPE"PLUMBING"
HDL_TAP"TRUE";
"B \NAC \NWC"4;
"S \NAC"
BN"4"47;
%"TAP"
"1","(3250,1575)","2","standard","I131";
;
CDS_LIB"standard"
BODY_TYPE"PLUMBING"
HDL_TAP"TRUE";
"B \NAC \NWC"4;
"S \NAC"
BN"6"125;
%"TAP"
"1","(3250,1775)","2","standard","I132";
;
CDS_LIB"standard"
BODY_TYPE"PLUMBING"
HDL_TAP"TRUE";
"B \NAC \NWC"4;
"S \NAC"
BN"7"124;
%"Q_CAP_DIFFBUS"
"2","(3975,1375)","2","pure_quanta","I133";
;
LOCATION"C954"
$SEC"1"
CDS_SEC"1"
VALUE"DIFF BUS_0.22UF"
PIN_NAMES_ROTATE"TRUE"
CDS_LIB"pure_quanta"
CDS_LMAN_SYM_OUTLINE"-25,50,25,-50"
VOLTAGE"6.3V"
MATERIAL"X6S"
PACK_TYPE"C0201"
TOLERANCE"20%"
PART_NUMBER"SP_CH4221MEE01"
LOCATION"C954";
"2"
$PN"2"46;
"1"
$PN"1"22;
%"Q_CAP_DIFFBUS"
"2","(3975,1525)","2","pure_quanta","I134";
;
LOCATION"C953"
$SEC"1"
CDS_SEC"1"
VALUE"DIFF BUS_0.22UF"
PIN_NAMES_ROTATE"TRUE"
CDS_LIB"pure_quanta"
CDS_LMAN_SYM_OUTLINE"-25,50,25,-50"
VOLTAGE"6.3V"
MATERIAL"X6S"
PACK_TYPE"C0201"
TOLERANCE"20%"
PART_NUMBER"SP_CH4221MEE01"
LOCATION"C953";
"2"
$PN"2"126;
"1"
$PN"1"143;
%"Q_CAP_DIFFBUS"
"2","(3975,1575)","2","pure_quanta","I135";
;
LOCATION"C952"
$SEC"1"
CDS_SEC"1"
VALUE"DIFF BUS_0.22UF"
PIN_NAMES_ROTATE"TRUE"
CDS_LIB"pure_quanta"
CDS_LMAN_SYM_OUTLINE"-25,50,25,-50"
VOLTAGE"6.3V"
MATERIAL"X6S"
PACK_TYPE"C0201"
TOLERANCE"20%"
PART_NUMBER"SP_CH4221MEE01"
LOCATION"C952";
"2"
$PN"2"125;
"1"
$PN"1"21;
%"Q_CAP_DIFFBUS"
"2","(3975,1725)","2","pure_quanta","I136";
;
LOCATION"C951"
$SEC"1"
CDS_SEC"1"
VALUE"DIFF BUS_0.22UF"
PIN_NAMES_ROTATE"TRUE"
CDS_LIB"pure_quanta"
CDS_LMAN_SYM_OUTLINE"-25,50,25,-50"
VOLTAGE"6.3V"
MATERIAL"X6S"
PACK_TYPE"C0201"
TOLERANCE"20%"
PART_NUMBER"SP_CH4221MEE01"
LOCATION"C951";
"2"
$PN"2"50;
"1"
$PN"1"142;
%"Q_CAP_DIFFBUS"
"2","(3975,1775)","2","pure_quanta","I137";
;
LOCATION"C950"
$SEC"1"
CDS_SEC"1"
VALUE"DIFF BUS_0.22UF"
PIN_NAMES_ROTATE"TRUE"
CDS_LMAN_SYM_OUTLINE"-25,50,25,-50"
CDS_LIB"pure_quanta"
VOLTAGE"6.3V"
MATERIAL"X6S"
PACK_TYPE"C0201"
TOLERANCE"20%"
PART_NUMBER"SP_CH4221MEE01"
LOCATION"C950";
"2"
$PN"2"124;
"1"
$PN"1"24;
%"TAP"
"1","(3000,2500)","2","standard","I138";
;
CDS_LIB"standard"
BODY_TYPE"PLUMBING"
HDL_TAP"TRUE";
"B \NAC \NWC"14;
"S \NAC"
BN"9"39;
%"TAP"
"1","(3000,2300)","2","standard","I139";
;
CDS_LIB"standard"
BODY_TYPE"PLUMBING"
HDL_TAP"TRUE";
"B \NAC \NWC"14;
"S \NAC"
BN"8"45;
%"TAP"
"1","(-1550,1325)","2","standard","I14";
;
CDS_LIB"standard"
BODY_TYPE"PLUMBING"
HDL_TAP"TRUE";
"B \NAC \NWC"10;
"S \NAC"
BN"5"88;
%"TAP"
"1","(3000,3100)","2","standard","I140";
;
CDS_LIB"standard"
BODY_TYPE"PLUMBING"
HDL_TAP"TRUE";
"B \NAC \NWC"14;
"S \NAC"
BN"12"42;
%"TAP"
"1","(3000,2900)","2","standard","I141";
;
CDS_LIB"standard"
BODY_TYPE"PLUMBING"
HDL_TAP"TRUE";
"B \NAC \NWC"14;
"S \NAC"
BN"11"41;
%"TAP"
"1","(3000,2700)","2","standard","I142";
;
CDS_LIB"standard"
BODY_TYPE"PLUMBING"
HDL_TAP"TRUE";
"B \NAC \NWC"14;
"S \NAC"
BN"10"40;
%"TAP"
"1","(3000,3300)","2","standard","I143";
;
CDS_LIB"standard"
BODY_TYPE"PLUMBING"
HDL_TAP"TRUE";
"B \NAC \NWC"14;
"S \NAC"
BN"13"43;
%"TAP"
"1","(3000,3500)","2","standard","I144";
;
CDS_LIB"standard"
BODY_TYPE"PLUMBING"
HDL_TAP"TRUE";
"B \NAC \NWC"14;
"S \NAC"
BN"14"37;
%"TAP"
"1","(3000,3700)","2","standard","I145";
;
CDS_LIB"standard"
BODY_TYPE"PLUMBING"
HDL_TAP"TRUE";
"B \NAC \NWC"14;
"S \NAC"
BN"15"44;
%"TAP"
"1","(3250,2350)","2","standard","I146";
;
CDS_LIB"standard"
BODY_TYPE"PLUMBING"
HDL_TAP"TRUE";
"B \NAC \NWC"5;
"S \NAC"
BN"8"38;
%"TAP"
"1","(3250,2550)","2","standard","I147";
;
CDS_LIB"standard"
BODY_TYPE"PLUMBING"
HDL_TAP"TRUE";
"B \NAC \NWC"5;
"S \NAC"
BN"9"49;
%"TAP"
"1","(3250,2750)","2","standard","I148";
;
CDS_LIB"standard"
BODY_TYPE"PLUMBING"
HDL_TAP"TRUE";
"B \NAC \NWC"5;
"S \NAC"
BN"10"122;
%"TAP"
"1","(3250,2950)","2","standard","I149";
;
CDS_LIB"standard"
BODY_TYPE"PLUMBING"
HDL_TAP"TRUE";
"B \NAC \NWC"5;
"S \NAC"
BN"11"48;
%"TAP"
"1","(-1550,1525)","2","standard","I15";
;
CDS_LIB"standard"
BODY_TYPE"PLUMBING"
HDL_TAP"TRUE";
"B \NAC \NWC"10;
"S \NAC"
BN"6"93;
%"TAP"
"1","(3250,3150)","2","standard","I150";
;
CDS_LIB"standard"
BODY_TYPE"PLUMBING"
HDL_TAP"TRUE";
"B \NAC \NWC"5;
"S \NAC"
BN"12"121;
%"Q_CAP_DIFFBUS"
"2","(3975,2300)","2","pure_quanta","I151";
;
LOCATION"C949"
$SEC"1"
CDS_SEC"1"
VALUE"DIFF BUS_0.22UF"
CDS_LMAN_SYM_OUTLINE"-25,50,25,-50"
CDS_LIB"pure_quanta"
PIN_NAMES_ROTATE"TRUE"
VOLTAGE"6.3V"
MATERIAL"X6S"
PACK_TYPE"C0201"
TOLERANCE"20%"
PART_NUMBER"SP_CH4221MEE01"
LOCATION"C949";
"2"
$PN"2"45;
"1"
$PN"1"32;
%"Q_CAP_DIFFBUS"
"2","(3975,2350)","2","pure_quanta","I152";
;
LOCATION"C948"
$SEC"1"
CDS_SEC"1"
VALUE"DIFF BUS_0.22UF"
CDS_LMAN_SYM_OUTLINE"-25,50,25,-50"
CDS_LIB"pure_quanta"
PIN_NAMES_ROTATE"TRUE"
VOLTAGE"6.3V"
MATERIAL"X6S"
PACK_TYPE"C0201"
TOLERANCE"20%"
PART_NUMBER"SP_CH4221MEE01"
LOCATION"C948";
"2"
$PN"2"38;
"1"
$PN"1"131;
%"Q_CAP_DIFFBUS"
"2","(3975,2500)","2","pure_quanta","I153";
;
LOCATION"C947"
$SEC"1"
CDS_SEC"1"
VALUE"DIFF BUS_0.22UF"
CDS_LMAN_SYM_OUTLINE"-25,50,25,-50"
CDS_LIB"pure_quanta"
PIN_NAMES_ROTATE"TRUE"
VOLTAGE"6.3V"
MATERIAL"X6S"
PACK_TYPE"C0201"
TOLERANCE"20%"
PART_NUMBER"SP_CH4221MEE01"
LOCATION"C947";
"2"
$PN"2"39;
"1"
$PN"1"31;
%"Q_CAP_DIFFBUS"
"2","(3975,2550)","2","pure_quanta","I154";
;
LOCATION"C946"
$SEC"1"
CDS_SEC"1"
VALUE"DIFF BUS_0.22UF"
CDS_LIB"pure_quanta"
CDS_LMAN_SYM_OUTLINE"-25,50,25,-50"
PIN_NAMES_ROTATE"TRUE"
VOLTAGE"6.3V"
MATERIAL"X6S"
PACK_TYPE"C0201"
TOLERANCE"20%"
PART_NUMBER"SP_CH4221MEE01"
LOCATION"C946";
"2"
$PN"2"49;
"1"
$PN"1"133;
%"Q_CAP_DIFFBUS"
"2","(3975,2700)","2","pure_quanta","I155";
;
LOCATION"C945"
$SEC"1"
CDS_SEC"1"
VALUE"DIFF BUS_0.22UF"
CDS_LMAN_SYM_OUTLINE"-25,50,25,-50"
CDS_LIB"pure_quanta"
PIN_NAMES_ROTATE"TRUE"
VOLTAGE"6.3V"
MATERIAL"X6S"
PACK_TYPE"C0201"
TOLERANCE"20%"
PART_NUMBER"SP_CH4221MEE01"
LOCATION"C945";
"2"
$PN"2"40;
"1"
$PN"1"34;
%"Q_CAP_DIFFBUS"
"2","(3975,2750)","2","pure_quanta","I156";
;
LOCATION"C944"
$SEC"1"
CDS_SEC"1"
VALUE"DIFF BUS_0.22UF"
CDS_LMAN_SYM_OUTLINE"-25,50,25,-50"
CDS_LIB"pure_quanta"
PIN_NAMES_ROTATE"TRUE"
VOLTAGE"6.3V"
MATERIAL"X6S"
PACK_TYPE"C0201"
TOLERANCE"20%"
PART_NUMBER"SP_CH4221MEE01"
LOCATION"C944";
"2"
$PN"2"122;
"1"
$PN"1"134;
%"Q_CAP_DIFFBUS"
"2","(3975,2900)","2","pure_quanta","I157";
;
LOCATION"C943"
$SEC"1"
CDS_SEC"1"
VALUE"DIFF BUS_0.22UF"
CDS_LIB"pure_quanta"
CDS_LMAN_SYM_OUTLINE"-25,50,25,-50"
PIN_NAMES_ROTATE"TRUE"
VOLTAGE"6.3V"
MATERIAL"X6S"
PACK_TYPE"C0201"
TOLERANCE"20%"
PART_NUMBER"SP_CH4221MEE01"
LOCATION"C943";
"2"
$PN"2"41;
"1"
$PN"1"33;
%"Q_CAP_DIFFBUS"
"2","(3975,2950)","2","pure_quanta","I158";
;
LOCATION"C942"
$SEC"1"
CDS_SEC"1"
VALUE"DIFF BUS_0.22UF"
CDS_LIB"pure_quanta"
CDS_LMAN_SYM_OUTLINE"-25,50,25,-50"
PIN_NAMES_ROTATE"TRUE"
VOLTAGE"6.3V"
MATERIAL"X6S"
PACK_TYPE"C0201"
TOLERANCE"20%"
PART_NUMBER"SP_CH4221MEE01"
LOCATION"C942";
"2"
$PN"2"48;
"1"
$PN"1"129;
%"Q_CAP_DIFFBUS"
"2","(3975,3100)","2","pure_quanta","I159";
;
LOCATION"C941"
$SEC"1"
CDS_SEC"1"
VALUE"DIFF BUS_0.22UF"
CDS_LMAN_SYM_OUTLINE"-25,50,25,-50"
CDS_LIB"pure_quanta"
PIN_NAMES_ROTATE"TRUE"
VOLTAGE"6.3V"
MATERIAL"X6S"
PACK_TYPE"C0201"
TOLERANCE"20%"
PART_NUMBER"SP_CH4221MEE01"
LOCATION"C941";
"2"
$PN"2"42;
"1"
$PN"1"30;
%"TAP"
"1","(-1300,1175)","2","standard","I16";
;
CDS_LIB"standard"
BODY_TYPE"PLUMBING"
HDL_TAP"TRUE";
"B \NAC \NWC"13;
"S \NAC"
BN"4"67;
%"Q_CAP_DIFFBUS"
"2","(3975,3150)","2","pure_quanta","I160";
;
LOCATION"C940"
$SEC"1"
CDS_SEC"1"
VALUE"DIFF BUS_0.22UF"
CDS_LMAN_SYM_OUTLINE"-25,50,25,-50"
CDS_LIB"pure_quanta"
PIN_NAMES_ROTATE"TRUE"
VOLTAGE"6.3V"
MATERIAL"X6S"
PACK_TYPE"C0201"
TOLERANCE"20%"
PART_NUMBER"SP_CH4221MEE01"
LOCATION"C940";
"2"
$PN"2"121;
"1"
$PN"1"130;
%"TAP"
"1","(3250,3350)","2","standard","I161";
;
CDS_LIB"standard"
BODY_TYPE"PLUMBING"
HDL_TAP"TRUE";
"B \NAC \NWC"5;
"S \NAC"
BN"13"123;
%"TAP"
"1","(3250,3550)","2","standard","I162";
;
CDS_LIB"standard"
BODY_TYPE"PLUMBING"
HDL_TAP"TRUE";
"B \NAC \NWC"5;
"S \NAC"
BN"14"36;
%"TAP"
"1","(3250,3750)","2","standard","I163";
;
CDS_LIB"standard"
BODY_TYPE"PLUMBING"
HDL_TAP"TRUE";
"B \NAC \NWC"5;
"S \NAC"
BN"15"35;
%"Q_CAP_DIFFBUS"
"2","(3975,3300)","2","pure_quanta","I164";
;
LOCATION"C939"
$SEC"1"
CDS_SEC"1"
VALUE"DIFF BUS_0.22UF"
CDS_LMAN_SYM_OUTLINE"-25,50,25,-50"
CDS_LIB"pure_quanta"
PIN_NAMES_ROTATE"TRUE"
VOLTAGE"6.3V"
MATERIAL"X6S"
PACK_TYPE"C0201"
TOLERANCE"20%"
PART_NUMBER"SP_CH4221MEE01"
LOCATION"C939";
"2"
$PN"2"43;
"1"
$PN"1"29;
%"Q_CAP_DIFFBUS"
"2","(3975,3350)","2","pure_quanta","I165";
;
LOCATION"C938"
$SEC"1"
CDS_SEC"1"
VALUE"DIFF BUS_0.22UF"
CDS_LMAN_SYM_OUTLINE"-25,50,25,-50"
CDS_LIB"pure_quanta"
PIN_NAMES_ROTATE"TRUE"
VOLTAGE"6.3V"
MATERIAL"X6S"
PACK_TYPE"C0201"
TOLERANCE"20%"
PART_NUMBER"SP_CH4221MEE01"
LOCATION"C938";
"2"
$PN"2"123;
"1"
$PN"1"135;
%"Q_CAP_DIFFBUS"
"2","(3975,3500)","2","pure_quanta","I166";
;
LOCATION"C937"
$SEC"1"
CDS_SEC"1"
VALUE"DIFF BUS_0.22UF"
CDS_LMAN_SYM_OUTLINE"-25,50,25,-50"
CDS_LIB"pure_quanta"
PIN_NAMES_ROTATE"TRUE"
VOLTAGE"6.3V"
MATERIAL"X6S"
PACK_TYPE"C0201"
TOLERANCE"20%"
PART_NUMBER"SP_CH4221MEE01"
LOCATION"C937";
"2"
$PN"2"37;
"1"
$PN"1"27;
%"Q_CAP_DIFFBUS"
"2","(3975,3550)","2","pure_quanta","I167";
;
LOCATION"C936"
$SEC"1"
CDS_SEC"1"
VALUE"DIFF BUS_0.22UF"
CDS_LMAN_SYM_OUTLINE"-25,50,25,-50"
CDS_LIB"pure_quanta"
PIN_NAMES_ROTATE"TRUE"
VOLTAGE"6.3V"
MATERIAL"X6S"
PACK_TYPE"C0201"
TOLERANCE"20%"
PART_NUMBER"SP_CH4221MEE01"
LOCATION"C936";
"2"
$PN"2"36;
"1"
$PN"1"132;
%"Q_CAP_DIFFBUS"
"2","(3975,3700)","2","pure_quanta","I168";
;
LOCATION"C935"
$SEC"1"
CDS_SEC"1"
VALUE"DIFF BUS_0.22UF"
CDS_LMAN_SYM_OUTLINE"-25,50,25,-50"
CDS_LIB"pure_quanta"
PIN_NAMES_ROTATE"TRUE"
VOLTAGE"6.3V"
MATERIAL"X6S"
PACK_TYPE"C0201"
TOLERANCE"20%"
PART_NUMBER"SP_CH4221MEE01"
LOCATION"C935";
"2"
$PN"2"44;
"1"
$PN"1"28;
%"Q_CAP_DIFFBUS"
"2","(3975,3750)","2","pure_quanta","I169";
;
LOCATION"C934"
$SEC"1"
CDS_SEC"1"
TOLERANCE"20%"
VALUE"DIFF BUS_0.22UF"
MATERIAL"X6S"
VOLTAGE"6.3V"
PACK_TYPE"C0201"
CDS_LIB"pure_quanta"
CDS_LMAN_SYM_OUTLINE"-25,50,25,-50"
PIN_NAMES_ROTATE"TRUE"
PART_NUMBER"SP_CH4221MEE01"
LOCATION"C934";
"2"
$PN"2"35;
"1"
$PN"1"136;
%"TAP"
"1","(-1300,1375)","2","standard","I17";
;
CDS_LIB"standard"
BODY_TYPE"PLUMBING"
HDL_TAP"TRUE";
"B \NAC \NWC"13;
"S \NAC"
BN"5"63;
%"TAP"
"1","(4525,575)","0","standard","I170";
;
CDS_LIB"standard"
BODY_TYPE"PLUMBING"
HDL_TAP"TRUE";
"B \NAC \NWC"16;
"S \NAC"
BN"1"25;
%"TAP"
"1","(4525,775)","0","standard","I171";
;
CDS_LIB"standard"
BODY_TYPE"PLUMBING"
HDL_TAP"TRUE";
"B \NAC \NWC"16;
"S \NAC"
BN"2"26;
%"TAP"
"1","(4525,975)","0","standard","I172";
;
CDS_LIB"standard"
BODY_TYPE"PLUMBING"
HDL_TAP"TRUE";
"B \NAC \NWC"16;
"S \NAC"
BN"3"20;
%"TAP"
"1","(4725,325)","0","standard","I173";
;
CDS_LIB"standard"
BODY_TYPE"PLUMBING"
HDL_TAP"TRUE";
"B \NAC \NWC"1;
"S \NAC"
BN"0"140;
%"TAP"
"1","(4725,525)","0","standard","I174";
;
CDS_LIB"standard"
BODY_TYPE"PLUMBING"
HDL_TAP"TRUE";
"B \NAC \NWC"1;
"S \NAC"
BN"1"137;
%"TAP"
"1","(4725,725)","0","standard","I175";
;
CDS_LIB"standard"
BODY_TYPE"PLUMBING"
HDL_TAP"TRUE";
"B \NAC \NWC"1;
"S \NAC"
BN"2"138;
%"TAP"
"1","(4725,925)","0","standard","I176";
;
CDS_LIB"standard"
BODY_TYPE"PLUMBING"
HDL_TAP"TRUE";
"B \NAC \NWC"1;
"S \NAC"
BN"3"139;
%"TAP"
"1","(4725,1125)","0","standard","I177";
;
CDS_LIB"standard"
BODY_TYPE"PLUMBING"
HDL_TAP"TRUE";
"B \NAC \NWC"1;
"S \NAC"
BN"4"144;
%"TAP"
"1","(4525,1375)","0","standard","I178";
;
CDS_LIB"standard"
BODY_TYPE"PLUMBING"
HDL_TAP"TRUE";
"B \NAC \NWC"16;
"S \NAC"
BN"5"22;
%"TAP"
"1","(4525,1175)","0","standard","I179";
;
CDS_LIB"standard"
BODY_TYPE"PLUMBING"
HDL_TAP"TRUE";
"B \NAC \NWC"16;
"S \NAC"
BN"4"23;
%"TAP"
"1","(-1300,1575)","2","standard","I18";
;
CDS_LIB"standard"
BODY_TYPE"PLUMBING"
HDL_TAP"TRUE";
"B \NAC \NWC"13;
"S \NAC"
BN"6"68;
%"TAP"
"1","(4525,1575)","0","standard","I180";
;
CDS_LIB"standard"
BODY_TYPE"PLUMBING"
HDL_TAP"TRUE";
"B \NAC \NWC"16;
"S \NAC"
BN"6"21;
%"TAP"
"1","(4525,1775)","0","standard","I181";
;
CDS_LIB"standard"
BODY_TYPE"PLUMBING"
HDL_TAP"TRUE";
"B \NAC \NWC"16;
"S \NAC"
BN"7"24;
%"TAP"
"1","(4725,1325)","0","standard","I182";
;
CDS_LIB"standard"
BODY_TYPE"PLUMBING"
HDL_TAP"TRUE";
"B \NAC \NWC"1;
"S \NAC"
BN"5"141;
%"TAP"
"1","(4725,1525)","0","standard","I183";
;
CDS_LIB"standard"
BODY_TYPE"PLUMBING"
HDL_TAP"TRUE";
"B \NAC \NWC"1;
"S \NAC"
BN"6"143;
%"TAP"
"1","(4725,1725)","0","standard","I184";
;
CDS_LIB"standard"
BODY_TYPE"PLUMBING"
HDL_TAP"TRUE";
"B \NAC \NWC"1;
"S \NAC"
BN"7"142;
%"TAP"
"1","(4525,2350)","0","standard","I187";
;
CDS_LIB"standard"
BODY_TYPE"PLUMBING"
HDL_TAP"TRUE";
"B \NAC \NWC"2;
"S \NAC"
BN"8"131;
%"TAP"
"1","(4525,2550)","0","standard","I188";
;
CDS_LIB"standard"
BODY_TYPE"PLUMBING"
HDL_TAP"TRUE";
"B \NAC \NWC"2;
"S \NAC"
BN"9"133;
%"TAP"
"1","(4525,2750)","0","standard","I189";
;
CDS_LIB"standard"
BODY_TYPE"PLUMBING"
HDL_TAP"TRUE";
"B \NAC \NWC"2;
"S \NAC"
BN"10"134;
%"TAP"
"1","(-1550,1725)","2","standard","I19";
;
CDS_LIB"standard"
BODY_TYPE"PLUMBING"
HDL_TAP"TRUE";
"B \NAC \NWC"10;
"S \NAC"
BN"7"83;
%"TAP"
"1","(4525,2950)","0","standard","I190";
;
CDS_LIB"standard"
BODY_TYPE"PLUMBING"
HDL_TAP"TRUE";
"B \NAC \NWC"2;
"S \NAC"
BN"11"129;
%"TAP"
"1","(4525,3150)","0","standard","I191";
;
CDS_LIB"standard"
BODY_TYPE"PLUMBING"
HDL_TAP"TRUE";
"B \NAC \NWC"2;
"S \NAC"
BN"12"130;
%"TAP"
"1","(4725,2300)","0","standard","I192";
;
CDS_LIB"standard"
BODY_TYPE"PLUMBING"
HDL_TAP"TRUE";
"B \NAC \NWC"15;
"S \NAC"
BN"8"32;
%"TAP"
"1","(4725,2500)","0","standard","I193";
;
CDS_LIB"standard"
BODY_TYPE"PLUMBING"
HDL_TAP"TRUE";
"B \NAC \NWC"15;
"S \NAC"
BN"9"31;
%"TAP"
"1","(4725,2700)","0","standard","I194";
;
CDS_LIB"standard"
BODY_TYPE"PLUMBING"
HDL_TAP"TRUE";
"B \NAC \NWC"15;
"S \NAC"
BN"10"34;
%"TAP"
"1","(4725,2900)","0","standard","I195";
;
CDS_LIB"standard"
BODY_TYPE"PLUMBING"
HDL_TAP"TRUE";
"B \NAC \NWC"15;
"S \NAC"
BN"11"33;
%"TAP"
"1","(4725,3100)","0","standard","I196";
;
CDS_LIB"standard"
BODY_TYPE"PLUMBING"
HDL_TAP"TRUE";
"B \NAC \NWC"15;
"S \NAC"
BN"12"30;
%"TAP"
"1","(4525,3350)","0","standard","I197";
;
CDS_LIB"standard"
BODY_TYPE"PLUMBING"
HDL_TAP"TRUE";
"B \NAC \NWC"2;
"S \NAC"
BN"13"135;
%"TAP"
"1","(4525,3550)","0","standard","I198";
;
CDS_LIB"standard"
BODY_TYPE"PLUMBING"
HDL_TAP"TRUE";
"B \NAC \NWC"2;
"S \NAC"
BN"14"132;
%"TAP"
"1","(4525,3750)","0","standard","I199";
;
CDS_LIB"standard"
BODY_TYPE"PLUMBING"
HDL_TAP"TRUE";
"B \NAC \NWC"2;
"S \NAC"
BN"15"136;
%"TAP"
"1","(-1300,1775)","2","standard","I20";
;
CDS_LIB"standard"
BODY_TYPE"PLUMBING"
HDL_TAP"TRUE";
"B \NAC \NWC"13;
"S \NAC"
BN"7"61;
%"TAP"
"1","(4725,3300)","0","standard","I200";
;
CDS_LIB"standard"
BODY_TYPE"PLUMBING"
HDL_TAP"TRUE";
"B \NAC \NWC"15;
"S \NAC"
BN"13"29;
%"TAP"
"1","(4725,3500)","0","standard","I201";
;
CDS_LIB"standard"
BODY_TYPE"PLUMBING"
HDL_TAP"TRUE";
"B \NAC \NWC"15;
"S \NAC"
BN"14"27;
%"TAP"
"1","(4725,3700)","0","standard","I202";
;
CDS_LIB"standard"
BODY_TYPE"PLUMBING"
HDL_TAP"TRUE";
"B \NAC \NWC"15;
"S \NAC"
BN"15"28;
%"TAP"
"1","(4525,375)","0","standard","I205";
;
CDS_LIB"standard"
BODY_TYPE"PLUMBING"
HDL_TAP"TRUE";
"B \NAC \NWC"16;
"S \NAC"
BN"0"19;
%"Q_CAP_DIFFBUS"
"2","(3975,1125)","2","pure_quanta","I206";
;
LOCATION"C957"
$SEC"1"
CDS_SEC"1"
VALUE"DIFF BUS_0.22UF"
PIN_NAMES_ROTATE"TRUE"
CDS_LIB"pure_quanta"
CDS_LMAN_SYM_OUTLINE"-25,50,25,-50"
VOLTAGE"6.3V"
MATERIAL"X6S"
PACK_TYPE"C0201"
TOLERANCE"20%"
PART_NUMBER"SP_CH4221MEE01"
LOCATION"C957";
"2"
$PN"2"116;
"1"
$PN"1"144;
%"Q_CAP_DIFFBUS"
"2","(3975,1175)","2","pure_quanta","I207";
;
LOCATION"C956"
$SEC"1"
CDS_SEC"1"
VALUE"DIFF BUS_0.22UF"
PIN_NAMES_ROTATE"TRUE"
CDS_LIB"pure_quanta"
CDS_LMAN_SYM_OUTLINE"-25,50,25,-50"
VOLTAGE"6.3V"
MATERIAL"X6S"
PACK_TYPE"C0201"
TOLERANCE"20%"
PART_NUMBER"SP_CH4221MEE01"
LOCATION"C956";
"2"
$PN"2"47;
"1"
$PN"1"23;
%"Q_CAP_DIFFBUS"
"2","(3975,1325)","2","pure_quanta","I208";
;
LOCATION"C955"
$SEC"1"
CDS_SEC"1"
VALUE"DIFF BUS_0.22UF"
PIN_NAMES_ROTATE"TRUE"
CDS_LIB"pure_quanta"
CDS_LMAN_SYM_OUTLINE"-25,50,25,-50"
VOLTAGE"6.3V"
MATERIAL"X6S"
PACK_TYPE"C0201"
TOLERANCE"20%"
PART_NUMBER"SP_CH4221MEE01"
LOCATION"C955";
"2"
$PN"2"127;
"1"
$PN"1"141;
%"Q_CAP_DIFFBUS"
"2","(-575,375)","2","pure_quanta","I21";
;
LOCATION"C932"
$SEC"1"
CDS_SEC"1"
VALUE"DIFF BUS_0.22UF"
PIN_NAMES_ROTATE"TRUE"
CDS_LIB"pure_quanta"
CDS_LMAN_SYM_OUTLINE"-25,50,25,-50"
VOLTAGE"6.3V"
MATERIAL"X6S"
PACK_TYPE"C0201"
TOLERANCE"20%"
PART_NUMBER"SP_CH4221MEE01"
LOCATION"C932";
"2"
$PN"2"66;
"1"
$PN"1"108;
%"Q_CAP_DIFFBUS"
"2","(-575,325)","2","pure_quanta","I22";
;
LOCATION"C933"
$SEC"1"
CDS_SEC"1"
VALUE"DIFF BUS_0.22UF"
PIN_NAMES_ROTATE"TRUE"
CDS_LIB"pure_quanta"
CDS_LMAN_SYM_OUTLINE"-25,50,25,-50"
VOLTAGE"6.3V"
MATERIAL"X6S"
PACK_TYPE"C0201"
TOLERANCE"20%"
PART_NUMBER"SP_CH4221MEE01"
LOCATION"C933";
"2"
$PN"2"91;
"1"
$PN"1"84;
%"Q_CAP_DIFFBUS"
"2","(-575,525)","2","pure_quanta","I23";
;
LOCATION"C931"
$SEC"1"
CDS_SEC"1"
VALUE"DIFF BUS_0.22UF"
PIN_NAMES_ROTATE"TRUE"
CDS_LIB"pure_quanta"
CDS_LMAN_SYM_OUTLINE"-25,50,25,-50"
VOLTAGE"6.3V"
MATERIAL"X6S"
PACK_TYPE"C0201"
TOLERANCE"20%"
PART_NUMBER"SP_CH4221MEE01"
LOCATION"C931";
"2"
$PN"2"92;
"1"
$PN"1"105;
%"Q_CAP_DIFFBUS"
"2","(-575,575)","2","pure_quanta","I24";
;
LOCATION"C930"
$SEC"1"
CDS_SEC"1"
VALUE"DIFF BUS_0.22UF"
PIN_NAMES_ROTATE"TRUE"
CDS_LMAN_SYM_OUTLINE"-25,50,25,-50"
CDS_LIB"pure_quanta"
VOLTAGE"6.3V"
MATERIAL"X6S"
PACK_TYPE"C0201"
TOLERANCE"20%"
PART_NUMBER"SP_CH4221MEE01"
LOCATION"C930";
"2"
$PN"2"62;
"1"
$PN"1"106;
%"Q_CAP_DIFFBUS"
"2","(-575,775)","2","pure_quanta","I25";
;
LOCATION"C928"
$SEC"1"
CDS_SEC"1"
VALUE"DIFF BUS_0.22UF"
PIN_NAMES_ROTATE"TRUE"
CDS_LIB"pure_quanta"
CDS_LMAN_SYM_OUTLINE"-25,50,25,-50"
VOLTAGE"6.3V"
MATERIAL"X6S"
PACK_TYPE"C0201"
TOLERANCE"20%"
PART_NUMBER"SP_CH4221MEE01"
LOCATION"C928";
"2"
$PN"2"65;
"1"
$PN"1"86;
%"Q_CAP_DIFFBUS"
"2","(-575,725)","2","pure_quanta","I26";
;
LOCATION"C929"
$SEC"1"
CDS_SEC"1"
VALUE"DIFF BUS_0.22UF"
PIN_NAMES_ROTATE"TRUE"
CDS_LIB"pure_quanta"
CDS_LMAN_SYM_OUTLINE"-25,50,25,-50"
VOLTAGE"6.3V"
MATERIAL"X6S"
PACK_TYPE"C0201"
TOLERANCE"20%"
PART_NUMBER"SP_CH4221MEE01"
LOCATION"C929";
"2"
$PN"2"94;
"1"
$PN"1"85;
%"Q_CAP_DIFFBUS"
"2","(-575,925)","2","pure_quanta","I27";
;
LOCATION"C927"
$SEC"1"
CDS_SEC"1"
VALUE"DIFF BUS_0.22UF"
PIN_NAMES_ROTATE"TRUE"
CDS_LMAN_SYM_OUTLINE"-25,50,25,-50"
CDS_LIB"pure_quanta"
VOLTAGE"6.3V"
MATERIAL"X6S"
PACK_TYPE"C0201"
TOLERANCE"20%"
PART_NUMBER"SP_CH4221MEE01"
LOCATION"C927";
"2"
$PN"2"89;
"1"
$PN"1"111;
%"Q_CAP_DIFFBUS"
"2","(-575,975)","2","pure_quanta","I28";
;
LOCATION"C926"
$SEC"1"
CDS_SEC"1"
VALUE"DIFF BUS_0.22UF"
PIN_NAMES_ROTATE"TRUE"
CDS_LMAN_SYM_OUTLINE"-25,50,25,-50"
CDS_LIB"pure_quanta"
VOLTAGE"6.3V"
MATERIAL"X6S"
PACK_TYPE"C0201"
TOLERANCE"20%"
PART_NUMBER"SP_CH4221MEE01"
LOCATION"C926";
"2"
$PN"2"64;
"1"
$PN"1"109;
%"Q_CAP_DIFFBUS"
"2","(-575,1125)","2","pure_quanta","I29";
;
LOCATION"C925"
$SEC"1"
CDS_SEC"1"
VALUE"DIFF BUS_0.22UF"
PIN_NAMES_ROTATE"TRUE"
CDS_LIB"pure_quanta"
CDS_LMAN_SYM_OUTLINE"-25,50,25,-50"
VOLTAGE"6.3V"
MATERIAL"X6S"
PACK_TYPE"C0201"
TOLERANCE"20%"
PART_NUMBER"SP_CH4221MEE01"
LOCATION"C925";
"2"
$PN"2"87;
"1"
$PN"1"110;
%"Q_CAP_DIFFBUS"
"2","(-575,1175)","2","pure_quanta","I30";
;
LOCATION"C924"
$SEC"1"
CDS_SEC"1"
VALUE"DIFF BUS_0.22UF"
PIN_NAMES_ROTATE"TRUE"
CDS_LIB"pure_quanta"
CDS_LMAN_SYM_OUTLINE"-25,50,25,-50"
VOLTAGE"6.3V"
MATERIAL"X6S"
PACK_TYPE"C0201"
TOLERANCE"20%"
PART_NUMBER"SP_CH4221MEE01"
LOCATION"C924";
"2"
$PN"2"67;
"1"
$PN"1"107;
%"Q_CAP_DIFFBUS"
"2","(-575,1325)","2","pure_quanta","I31";
;
LOCATION"C923"
$SEC"1"
CDS_SEC"1"
VALUE"DIFF BUS_0.22UF"
PIN_NAMES_ROTATE"TRUE"
CDS_LIB"pure_quanta"
CDS_LMAN_SYM_OUTLINE"-25,50,25,-50"
VOLTAGE"6.3V"
MATERIAL"X6S"
PACK_TYPE"C0201"
TOLERANCE"20%"
PART_NUMBER"SP_CH4221MEE01"
LOCATION"C923";
"2"
$PN"2"88;
"1"
$PN"1"104;
%"Q_CAP_DIFFBUS"
"2","(-575,1375)","2","pure_quanta","I32";
;
LOCATION"C922"
$SEC"1"
CDS_SEC"1"
VALUE"DIFF BUS_0.22UF"
PIN_NAMES_ROTATE"TRUE"
CDS_LIB"pure_quanta"
CDS_LMAN_SYM_OUTLINE"-25,50,25,-50"
VOLTAGE"6.3V"
MATERIAL"X6S"
PACK_TYPE"C0201"
TOLERANCE"20%"
PART_NUMBER"SP_CH4221MEE01"
LOCATION"C922";
"2"
$PN"2"63;
"1"
$PN"1"103;
%"Q_CAP_DIFFBUS"
"2","(-575,1525)","2","pure_quanta","I33";
;
LOCATION"C921"
$SEC"1"
CDS_SEC"1"
VALUE"DIFF BUS_0.22UF"
PIN_NAMES_ROTATE"TRUE"
CDS_LIB"pure_quanta"
CDS_LMAN_SYM_OUTLINE"-25,50,25,-50"
VOLTAGE"6.3V"
MATERIAL"X6S"
PACK_TYPE"C0201"
TOLERANCE"20%"
PART_NUMBER"SP_CH4221MEE01"
LOCATION"C921";
"2"
$PN"2"93;
"1"
$PN"1"77;
%"Q_CAP_DIFFBUS"
"2","(-575,1575)","2","pure_quanta","I34";
;
LOCATION"C920"
$SEC"1"
CDS_SEC"1"
VALUE"DIFF BUS_0.22UF"
PIN_NAMES_ROTATE"TRUE"
CDS_LIB"pure_quanta"
CDS_LMAN_SYM_OUTLINE"-25,50,25,-50"
VOLTAGE"6.3V"
MATERIAL"X6S"
PACK_TYPE"C0201"
TOLERANCE"20%"
PART_NUMBER"SP_CH4221MEE01"
LOCATION"C920";
"2"
$PN"2"68;
"1"
$PN"1"78;
%"Q_CAP_DIFFBUS"
"2","(-575,1775)","2","pure_quanta","I35";
;
LOCATION"C918"
$SEC"1"
CDS_SEC"1"
VALUE"DIFF BUS_0.22UF"
PIN_NAMES_ROTATE"TRUE"
CDS_LMAN_SYM_OUTLINE"-25,50,25,-50"
CDS_LIB"pure_quanta"
VOLTAGE"6.3V"
MATERIAL"X6S"
PACK_TYPE"C0201"
TOLERANCE"20%"
PART_NUMBER"SP_CH4221MEE01"
LOCATION"C918";
"2"
$PN"2"61;
"1"
$PN"1"80;
%"Q_CAP_DIFFBUS"
"2","(-575,1725)","2","pure_quanta","I36";
;
LOCATION"C919"
$SEC"1"
CDS_SEC"1"
VALUE"DIFF BUS_0.22UF"
PIN_NAMES_ROTATE"TRUE"
CDS_LIB"pure_quanta"
CDS_LMAN_SYM_OUTLINE"-25,50,25,-50"
VOLTAGE"6.3V"
MATERIAL"X6S"
PACK_TYPE"C0201"
TOLERANCE"20%"
PART_NUMBER"SP_CH4221MEE01"
LOCATION"C919";
"2"
$PN"2"83;
"1"
$PN"1"79;
%"TAP"
"1","(-1550,2300)","2","standard","I37";
;
CDS_LIB"standard"
BODY_TYPE"PLUMBING"
HDL_TAP"TRUE";
"B \NAC \NWC"11;
"S \NAC"
BN"8"57;
%"TAP"
"1","(-1550,2500)","2","standard","I38";
;
CDS_LIB"standard"
BODY_TYPE"PLUMBING"
HDL_TAP"TRUE";
"B \NAC \NWC"11;
"S \NAC"
BN"9"76;
%"TAP"
"1","(-1300,2350)","2","standard","I39";
;
CDS_LIB"standard"
BODY_TYPE"PLUMBING"
HDL_TAP"TRUE";
"B \NAC \NWC"12;
"S \NAC"
BN"8"52;
%"TAP"
"1","(-1300,2550)","2","standard","I40";
;
CDS_LIB"standard"
BODY_TYPE"PLUMBING"
HDL_TAP"TRUE";
"B \NAC \NWC"12;
"S \NAC"
BN"9"72;
%"TAP"
"1","(-1550,2700)","2","standard","I41";
;
CDS_LIB"standard"
BODY_TYPE"PLUMBING"
HDL_TAP"TRUE";
"B \NAC \NWC"11;
"S \NAC"
BN"10"56;
%"TAP"
"1","(-1550,2900)","2","standard","I42";
;
CDS_LIB"standard"
BODY_TYPE"PLUMBING"
HDL_TAP"TRUE";
"B \NAC \NWC"11;
"S \NAC"
BN"11"53;
%"TAP"
"1","(-1550,3100)","2","standard","I43";
;
CDS_LIB"standard"
BODY_TYPE"PLUMBING"
HDL_TAP"TRUE";
"B \NAC \NWC"11;
"S \NAC"
BN"12"73;
%"TAP"
"1","(-1300,2750)","2","standard","I44";
;
CDS_LIB"standard"
BODY_TYPE"PLUMBING"
HDL_TAP"TRUE";
"B \NAC \NWC"12;
"S \NAC"
BN"10"58;
%"TAP"
"1","(-1300,2950)","2","standard","I45";
;
CDS_LIB"standard"
BODY_TYPE"PLUMBING"
HDL_TAP"TRUE";
"B \NAC \NWC"12;
"S \NAC"
BN"11"71;
%"TAP"
"1","(-1300,3150)","2","standard","I46";
;
CDS_LIB"standard"
BODY_TYPE"PLUMBING"
HDL_TAP"TRUE";
"B \NAC \NWC"12;
"S \NAC"
BN"12"70;
%"TAP"
"1","(-1550,3300)","2","standard","I47";
;
CDS_LIB"standard"
BODY_TYPE"PLUMBING"
HDL_TAP"TRUE";
"B \NAC \NWC"11;
"S \NAC"
BN"13"74;
%"TAP"
"1","(-1550,3500)","2","standard","I48";
;
CDS_LIB"standard"
BODY_TYPE"PLUMBING"
HDL_TAP"TRUE";
"B \NAC \NWC"11;
"S \NAC"
BN"14"75;
%"TAP"
"1","(-1550,3700)","2","standard","I49";
;
CDS_LIB"standard"
BODY_TYPE"PLUMBING"
HDL_TAP"TRUE";
"B \NAC \NWC"11;
"S \NAC"
BN"15"18;
%"TAP"
"1","(-1550,325)","2","standard","I5";
;
CDS_LIB"standard"
BODY_TYPE"PLUMBING"
HDL_TAP"TRUE";
"B \NAC \NWC"10;
"S \NAC"
BN"0"91;
%"TAP"
"1","(-1300,3350)","2","standard","I50";
;
CDS_LIB"standard"
BODY_TYPE"PLUMBING"
HDL_TAP"TRUE";
"B \NAC \NWC"12;
"S \NAC"
BN"13"69;
%"TAP"
"1","(-1300,3550)","2","standard","I51";
;
CDS_LIB"standard"
BODY_TYPE"PLUMBING"
HDL_TAP"TRUE";
"B \NAC \NWC"12;
"S \NAC"
BN"14"59;
%"TAP"
"1","(-1300,3750)","2","standard","I52";
;
CDS_LIB"standard"
BODY_TYPE"PLUMBING"
HDL_TAP"TRUE";
"B \NAC \NWC"12;
"S \NAC"
BN"15"60;
%"Q_CAP_DIFFBUS"
"2","(-575,2350)","2","pure_quanta","I53";
;
LOCATION"C916"
$SEC"1"
CDS_SEC"1"
VALUE"DIFF BUS_0.22UF"
CDS_LMAN_SYM_OUTLINE"-25,50,25,-50"
CDS_LIB"pure_quanta"
PIN_NAMES_ROTATE"TRUE"
VOLTAGE"6.3V"
MATERIAL"X6S"
PACK_TYPE"C0201"
TOLERANCE"20%"
PART_NUMBER"SP_CH4221MEE01"
LOCATION"C916";
"2"
$PN"2"52;
"1"
$PN"1"81;
%"Q_CAP_DIFFBUS"
"2","(-575,2300)","2","pure_quanta","I54";
;
LOCATION"C917"
$SEC"1"
CDS_SEC"1"
VALUE"DIFF BUS_0.22UF"
CDS_LMAN_SYM_OUTLINE"-25,50,25,-50"
CDS_LIB"pure_quanta"
PIN_NAMES_ROTATE"TRUE"
VOLTAGE"6.3V"
MATERIAL"X6S"
PACK_TYPE"C0201"
TOLERANCE"20%"
PART_NUMBER"SP_CH4221MEE01"
LOCATION"C917";
"2"
$PN"2"57;
"1"
$PN"1"51;
%"Q_CAP_DIFFBUS"
"2","(-575,2500)","2","pure_quanta","I55";
;
LOCATION"C915"
$SEC"1"
CDS_SEC"1"
VALUE"DIFF BUS_0.22UF"
CDS_LMAN_SYM_OUTLINE"-25,50,25,-50"
CDS_LIB"pure_quanta"
PIN_NAMES_ROTATE"TRUE"
VOLTAGE"6.3V"
MATERIAL"X6S"
PACK_TYPE"C0201"
TOLERANCE"20%"
PART_NUMBER"SP_CH4221MEE01"
LOCATION"C915";
"2"
$PN"2"76;
"1"
$PN"1"82;
%"Q_CAP_DIFFBUS"
"2","(-575,2550)","2","pure_quanta","I56";
;
LOCATION"C914"
$SEC"1"
CDS_SEC"1"
VALUE"DIFF BUS_0.22UF"
CDS_LIB"pure_quanta"
CDS_LMAN_SYM_OUTLINE"-25,50,25,-50"
PIN_NAMES_ROTATE"TRUE"
VOLTAGE"6.3V"
MATERIAL"X6S"
PACK_TYPE"C0201"
TOLERANCE"20%"
PART_NUMBER"SP_CH4221MEE01"
LOCATION"C914";
"2"
$PN"2"72;
"1"
$PN"1"90;
%"Q_CAP_DIFFBUS"
"2","(-575,2700)","2","pure_quanta","I57";
;
LOCATION"C913"
$SEC"1"
CDS_SEC"1"
VALUE"DIFF BUS_0.22UF"
CDS_LMAN_SYM_OUTLINE"-25,50,25,-50"
CDS_LIB"pure_quanta"
PIN_NAMES_ROTATE"TRUE"
VOLTAGE"6.3V"
MATERIAL"X6S"
PACK_TYPE"C0201"
TOLERANCE"20%"
PART_NUMBER"SP_CH4221MEE01"
LOCATION"C913";
"2"
$PN"2"56;
"1"
$PN"1"55;
%"Q_CAP_DIFFBUS"
"2","(-575,2750)","2","pure_quanta","I58";
;
LOCATION"C912"
$SEC"1"
CDS_SEC"1"
VALUE"DIFF BUS_0.22UF"
CDS_LMAN_SYM_OUTLINE"-25,50,25,-50"
CDS_LIB"pure_quanta"
PIN_NAMES_ROTATE"TRUE"
VOLTAGE"6.3V"
MATERIAL"X6S"
PACK_TYPE"C0201"
TOLERANCE"20%"
PART_NUMBER"SP_CH4221MEE01"
LOCATION"C912";
"2"
$PN"2"58;
"1"
$PN"1"112;
%"Q_CAP_DIFFBUS"
"2","(-575,2900)","2","pure_quanta","I59";
;
LOCATION"C911"
$SEC"1"
CDS_SEC"1"
VALUE"DIFF BUS_0.22UF"
CDS_LIB"pure_quanta"
CDS_LMAN_SYM_OUTLINE"-25,50,25,-50"
PIN_NAMES_ROTATE"TRUE"
VOLTAGE"6.3V"
MATERIAL"X6S"
PACK_TYPE"C0201"
TOLERANCE"20%"
PART_NUMBER"SP_CH4221MEE01"
LOCATION"C911";
"2"
$PN"2"53;
"1"
$PN"1"54;
%"TAP"
"1","(-1550,525)","2","standard","I6";
;
CDS_LIB"standard"
BODY_TYPE"PLUMBING"
HDL_TAP"TRUE";
"B \NAC \NWC"10;
"S \NAC"
BN"1"92;
%"Q_CAP_DIFFBUS"
"2","(-575,2950)","2","pure_quanta","I60";
;
LOCATION"C910"
$SEC"1"
CDS_SEC"1"
VALUE"DIFF BUS_0.22UF"
CDS_LIB"pure_quanta"
CDS_LMAN_SYM_OUTLINE"-25,50,25,-50"
PIN_NAMES_ROTATE"TRUE"
VOLTAGE"6.3V"
MATERIAL"X6S"
PACK_TYPE"C0201"
TOLERANCE"20%"
PART_NUMBER"SP_CH4221MEE01"
LOCATION"C910";
"2"
$PN"2"71;
"1"
$PN"1"98;
%"Q_CAP_DIFFBUS"
"2","(-575,3100)","2","pure_quanta","I61";
;
LOCATION"C909"
$SEC"1"
CDS_SEC"1"
VALUE"DIFF BUS_0.22UF"
CDS_LMAN_SYM_OUTLINE"-25,50,25,-50"
CDS_LIB"pure_quanta"
PIN_NAMES_ROTATE"TRUE"
VOLTAGE"6.3V"
MATERIAL"X6S"
PACK_TYPE"C0201"
TOLERANCE"20%"
PART_NUMBER"SP_CH4221MEE01"
LOCATION"C909";
"2"
$PN"2"73;
"1"
$PN"1"101;
%"Q_CAP_DIFFBUS"
"2","(-575,3150)","2","pure_quanta","I62";
;
LOCATION"C908"
$SEC"1"
CDS_SEC"1"
VALUE"DIFF BUS_0.22UF"
CDS_LMAN_SYM_OUTLINE"-25,50,25,-50"
CDS_LIB"pure_quanta"
PIN_NAMES_ROTATE"TRUE"
VOLTAGE"6.3V"
MATERIAL"X6S"
PACK_TYPE"C0201"
TOLERANCE"20%"
PART_NUMBER"SP_CH4221MEE01"
LOCATION"C908";
"2"
$PN"2"70;
"1"
$PN"1"100;
%"Q_CAP_DIFFBUS"
"2","(-575,3350)","2","pure_quanta","I63";
;
LOCATION"C906"
$SEC"1"
CDS_SEC"1"
VALUE"DIFF BUS_0.22UF"
CDS_LMAN_SYM_OUTLINE"-25,50,25,-50"
CDS_LIB"pure_quanta"
PIN_NAMES_ROTATE"TRUE"
VOLTAGE"6.3V"
MATERIAL"X6S"
PACK_TYPE"C0201"
TOLERANCE"20%"
PART_NUMBER"SP_CH4221MEE01"
LOCATION"C906";
"2"
$PN"2"69;
"1"
$PN"1"95;
%"Q_CAP_DIFFBUS"
"2","(-575,3300)","2","pure_quanta","I64";
;
LOCATION"C907"
$SEC"1"
CDS_SEC"1"
VALUE"DIFF BUS_0.22UF"
CDS_LMAN_SYM_OUTLINE"-25,50,25,-50"
CDS_LIB"pure_quanta"
PIN_NAMES_ROTATE"TRUE"
VOLTAGE"6.3V"
MATERIAL"X6S"
PACK_TYPE"C0201"
TOLERANCE"20%"
PART_NUMBER"SP_CH4221MEE01"
LOCATION"C907";
"2"
$PN"2"74;
"1"
$PN"1"99;
%"Q_CAP_DIFFBUS"
"2","(-575,3500)","2","pure_quanta","I65";
;
LOCATION"C905"
$SEC"1"
CDS_SEC"1"
VALUE"DIFF BUS_0.22UF"
CDS_LMAN_SYM_OUTLINE"-25,50,25,-50"
CDS_LIB"pure_quanta"
PIN_NAMES_ROTATE"TRUE"
VOLTAGE"6.3V"
MATERIAL"X6S"
PACK_TYPE"C0201"
TOLERANCE"20%"
PART_NUMBER"SP_CH4221MEE01"
LOCATION"C905";
"2"
$PN"2"75;
"1"
$PN"1"96;
%"Q_CAP_DIFFBUS"
"2","(-575,3550)","2","pure_quanta","I66";
;
LOCATION"C904"
$SEC"1"
CDS_SEC"1"
VALUE"DIFF BUS_0.22UF"
CDS_LMAN_SYM_OUTLINE"-25,50,25,-50"
CDS_LIB"pure_quanta"
PIN_NAMES_ROTATE"TRUE"
VOLTAGE"6.3V"
MATERIAL"X6S"
PACK_TYPE"C0201"
TOLERANCE"20%"
PART_NUMBER"SP_CH4221MEE01"
LOCATION"C904";
"2"
$PN"2"59;
"1"
$PN"1"102;
%"Q_CAP_DIFFBUS"
"2","(-575,3700)","2","pure_quanta","I67";
;
LOCATION"C903"
$SEC"1"
CDS_SEC"1"
VALUE"DIFF BUS_0.22UF"
CDS_LMAN_SYM_OUTLINE"-25,50,25,-50"
CDS_LIB"pure_quanta"
PIN_NAMES_ROTATE"TRUE"
VOLTAGE"6.3V"
MATERIAL"X6S"
PACK_TYPE"C0201"
TOLERANCE"20%"
PART_NUMBER"SP_CH4221MEE01"
LOCATION"C903";
"2"
$PN"2"18;
"1"
$PN"1"97;
%"Q_CAP_DIFFBUS"
"2","(-575,3750)","2","pure_quanta","I68";
;
LOCATION"C902"
$SEC"1"
CDS_SEC"1"
MATERIAL"X6S"
TOLERANCE"20%"
VOLTAGE"6.3V"
PACK_TYPE"C0201"
VALUE"DIFF BUS_0.22UF"
CDS_LIB"pure_quanta"
CDS_LMAN_SYM_OUTLINE"-25,50,25,-50"
PIN_NAMES_ROTATE"TRUE"
PART_NUMBER"SP_CH4221MEE01"
LOCATION"C902";
"2"
$PN"2"60;
"1"
$PN"1"17;
%"TAP"
"1","(-25,3550)","0","standard","I69";
;
CDS_LIB"standard"
BODY_TYPE"PLUMBING"
HDL_TAP"TRUE";
"B \NAC \NWC"6;
"S \NAC"
BN"14"102;
%"TAP"
"1","(-1300,375)","2","standard","I7";
;
CDS_LIB"standard"
BODY_TYPE"PLUMBING"
HDL_TAP"TRUE";
"B \NAC \NWC"13;
"S \NAC"
BN"0"66;
%"TAP"
"1","(-25,2950)","0","standard","I70";
;
CDS_LIB"standard"
BODY_TYPE"PLUMBING"
HDL_TAP"TRUE";
"B \NAC \NWC"6;
"S \NAC"
BN"11"98;
%"TAP"
"1","(-25,3350)","0","standard","I71";
;
CDS_LIB"standard"
BODY_TYPE"PLUMBING"
HDL_TAP"TRUE";
"B \NAC \NWC"6;
"S \NAC"
BN"13"95;
%"TAP"
"1","(-25,3150)","0","standard","I72";
;
CDS_LIB"standard"
BODY_TYPE"PLUMBING"
HDL_TAP"TRUE";
"B \NAC \NWC"6;
"S \NAC"
BN"12"100;
%"TAP"
"1","(-25,2750)","0","standard","I73";
;
CDS_LIB"standard"
BODY_TYPE"PLUMBING"
HDL_TAP"TRUE";
"B \NAC \NWC"6;
"S \NAC"
BN"10"112;
%"TAP"
"1","(-25,2350)","0","standard","I74";
;
CDS_LIB"standard"
BODY_TYPE"PLUMBING"
HDL_TAP"TRUE";
"B \NAC \NWC"6;
"S \NAC"
BN"8"81;
%"TAP"
"1","(-25,2550)","0","standard","I75";
;
CDS_LIB"standard"
BODY_TYPE"PLUMBING"
HDL_TAP"TRUE";
"B \NAC \NWC"6;
"S \NAC"
BN"9"90;
%"TAP"
"1","(-25,1775)","0","standard","I76";
;
CDS_LIB"standard"
BODY_TYPE"PLUMBING"
HDL_TAP"TRUE";
"B \NAC \NWC"8;
"S \NAC"
BN"7"80;
%"TAP"
"1","(-25,1375)","0","standard","I77";
;
CDS_LIB"standard"
BODY_TYPE"PLUMBING"
HDL_TAP"TRUE";
"B \NAC \NWC"8;
"S \NAC"
BN"5"103;
%"TAP"
"1","(-25,1575)","0","standard","I78";
;
CDS_LIB"standard"
BODY_TYPE"PLUMBING"
HDL_TAP"TRUE";
"B \NAC \NWC"8;
"S \NAC"
BN"6"78;
%"TAP"
"1","(-25,975)","0","standard","I79";
;
CDS_LIB"standard"
BODY_TYPE"PLUMBING"
HDL_TAP"TRUE";
"B \NAC \NWC"8;
"S \NAC"
BN"3"109;
%"TAP"
"1","(-1300,575)","2","standard","I8";
;
CDS_LIB"standard"
BODY_TYPE"PLUMBING"
HDL_TAP"TRUE";
"B \NAC \NWC"13;
"S \NAC"
BN"1"62;
%"TAP"
"1","(-25,1175)","0","standard","I80";
;
CDS_LIB"standard"
BODY_TYPE"PLUMBING"
HDL_TAP"TRUE";
"B \NAC \NWC"8;
"S \NAC"
BN"4"107;
%"TAP"
"1","(-25,775)","0","standard","I81";
;
CDS_LIB"standard"
BODY_TYPE"PLUMBING"
HDL_TAP"TRUE";
"B \NAC \NWC"8;
"S \NAC"
BN"2"86;
%"TAP"
"1","(-25,575)","0","standard","I82";
;
CDS_LIB"standard"
BODY_TYPE"PLUMBING"
HDL_TAP"TRUE";
"B \NAC \NWC"8;
"S \NAC"
BN"1"106;
%"TAP"
"1","(-25,375)","0","standard","I83";
;
CDS_LIB"standard"
BODY_TYPE"PLUMBING"
HDL_TAP"TRUE";
"B \NAC \NWC"8;
"S \NAC"
BN"0"108;
%"TAP"
"1","(-25,3750)","0","standard","I84";
;
CDS_LIB"standard"
BODY_TYPE"PLUMBING"
HDL_TAP"TRUE";
"B \NAC \NWC"6;
"S \NAC"
BN"15"17;
%"TAP"
"1","(175,325)","0","standard","I85";
;
CDS_LIB"standard"
BODY_TYPE"PLUMBING"
HDL_TAP"TRUE";
"B \NAC \NWC"7;
"S \NAC"
BN"0"84;
%"TAP"
"1","(175,525)","0","standard","I86";
;
CDS_LIB"standard"
BODY_TYPE"PLUMBING"
HDL_TAP"TRUE";
"B \NAC \NWC"7;
"S \NAC"
BN"1"105;
%"TAP"
"1","(175,725)","0","standard","I87";
;
CDS_LIB"standard"
BODY_TYPE"PLUMBING"
HDL_TAP"TRUE";
"B \NAC \NWC"7;
"S \NAC"
BN"2"85;
%"TAP"
"1","(175,925)","0","standard","I88";
;
CDS_LIB"standard"
BODY_TYPE"PLUMBING"
HDL_TAP"TRUE";
"B \NAC \NWC"7;
"S \NAC"
BN"3"111;
%"TAP"
"1","(175,1125)","0","standard","I89";
;
CDS_LIB"standard"
BODY_TYPE"PLUMBING"
HDL_TAP"TRUE";
"B \NAC \NWC"7;
"S \NAC"
BN"4"110;
%"TAP"
"1","(-1550,725)","2","standard","I9";
;
CDS_LIB"standard"
BODY_TYPE"PLUMBING"
HDL_TAP"TRUE";
"B \NAC \NWC"10;
"S \NAC"
BN"2"94;
%"TAP"
"1","(175,1325)","0","standard","I90";
;
CDS_LIB"standard"
BODY_TYPE"PLUMBING"
HDL_TAP"TRUE";
"B \NAC \NWC"7;
"S \NAC"
BN"5"104;
%"TAP"
"1","(175,1525)","0","standard","I91";
;
CDS_LIB"standard"
BODY_TYPE"PLUMBING"
HDL_TAP"TRUE";
"B \NAC \NWC"7;
"S \NAC"
BN"6"77;
%"TAP"
"1","(175,1725)","0","standard","I92";
;
CDS_LIB"standard"
BODY_TYPE"PLUMBING"
HDL_TAP"TRUE";
"B \NAC \NWC"7;
"S \NAC"
BN"7"79;
%"TAP"
"1","(175,2300)","0","standard","I97";
;
CDS_LIB"standard"
BODY_TYPE"PLUMBING"
HDL_TAP"TRUE";
"B \NAC \NWC"9;
"S \NAC"
BN"8"51;
%"TAP"
"1","(175,2500)","0","standard","I98";
;
CDS_LIB"standard"
BODY_TYPE"PLUMBING"
HDL_TAP"TRUE";
"B \NAC \NWC"9;
"S \NAC"
BN"9"82;
%"TAP"
"1","(175,2900)","0","standard","I99";
;
CDS_LIB"standard"
BODY_TYPE"PLUMBING"
HDL_TAP"TRUE";
"B \NAC \NWC"9;
"S \NAC"
BN"11"54;
END.
